(kicad_pcb
	(version 20260206)
	(generator "pcbnew")
	(generator_version "10.0")
	(general
		(thickness 1.6)
		(legacy_teardrops no)
	)
	(paper "A4")
	(title_block
		(title "01162023_DA0F0TEBIF0_F0T_Expander_BD_F_brd_V02_OCP.brd")
		(comment 1 "Grand Teton / footprints 8836-8843 of 9728")
	)
	(layers
		(0 "F.Cu" signal "TOP")
		(4 "In1.Cu" signal "GND")
		(6 "In2.Cu" signal "VCC")
		(8 "In3.Cu" signal "VCC1")
		(10 "In4.Cu" signal "GND1")
		(12 "In5.Cu" signal "IN1")
		(14 "In6.Cu" signal "GND2")
		(16 "In7.Cu" signal "IN2")
		(18 "In8.Cu" signal "GND3")
		(20 "In9.Cu" signal "IN3")
		(22 "In10.Cu" signal "GND4")
		(24 "In11.Cu" signal "IN4")
		(26 "In12.Cu" signal "GND5")
		(28 "In13.Cu" signal "IN5")
		(30 "In14.Cu" signal "GND6")
		(32 "In15.Cu" signal "IN6")
		(34 "In16.Cu" signal "GND7")
		(2 "B.Cu" signal "BOTTOM")
		(9 "F.Adhes" user "F.Adhesive")
		(11 "B.Adhes" user "B.Adhesive")
		(13 "F.Paste" user "Package Geometry/Pastemask Top")
		(15 "B.Paste" user "Package Geometry/Pastemask Bottom")
		(5 "F.SilkS" user "Ref Des/Silkscreen Top")
		(7 "B.SilkS" user "Ref Des/Silkscreen Bottom")
		(1 "F.Mask" user "Board Geometry/Soldermask Top")
		(3 "B.Mask" user "Board Geometry/Soldermask Bottom")
		(17 "Dwgs.User" user "User.Drawings")
		(19 "Cmts.User" user "User.Comments")
		(21 "Eco1.User" user "User.Eco1")
		(23 "Eco2.User" user "User.Eco2")
		(25 "Edge.Cuts" user "Board Geometry/Outline")
		(27 "Margin" user)
		(31 "F.CrtYd" user "Package Geometry/Place Bound Top")
		(29 "B.CrtYd" user "Package Geometry/Place Bound Bottom")
		(35 "F.Fab" user "Ref Des/Assembly Top")
		(33 "B.Fab" user "Ref Des/Assembly Bottom")
	)
	(footprint ""
		(layer "B.Cu")
		(at 407.949908 -292.099746 90)
		(property "Reference" "C1988"
			(at 0 0 90)
			(layer "B.SilkS")
			(hide yes)
			(effects
				(font
					(size 1.27 1.27)
				)
				(justify mirror)
			)
		)
		(property "Value" ""
			(at 0 0 90)
			(layer "B.Fab")
			(effects
				(font
					(size 1.27 1.27)
				)
				(justify mirror)
			)
		)
		(duplicate_pad_numbers_are_jumpers no)
		(fp_line
			(start 0.299974 -0.150114)
			(end -0.299974 -0.150114)
			(stroke
				(width 0.1)
				(type default)
			)
			(layer "B.Fab")
		)
		(fp_line
			(start -0.299974 -0.150114)
			(end -0.299974 0.150114)
			(stroke
				(width 0.1)
				(type default)
			)
			(layer "B.Fab")
		)
		(fp_line
			(start 0.299974 0.150114)
			(end 0.299974 -0.150114)
			(stroke
				(width 0.1)
				(type default)
			)
			(layer "B.Fab")
		)
		(fp_line
			(start -0.299974 0.150114)
			(end 0.299974 0.150114)
			(stroke
				(width 0.1)
				(type default)
			)
			(layer "B.Fab")
		)
		(pad "1" smd rect
			(at 0.2667 0 270)
			(size 0.3048 0.381)
			(layers "B.Cu" "B.Mask" "B.Paste")
			(net "P0V8_SERDES_VDDA_PEX3")
		)
		(pad "2" smd rect
			(at -0.2667 0 270)
			(size 0.3048 0.381)
			(layers "B.Cu" "B.Mask" "B.Paste")
			(net "GND")
		)
	)
	(footprint ""
		(layer "B.Cu")
		(at 213.106 -196.977 90)
		(property "Reference" "R6311"
			(at 0 0 90)
			(layer "B.SilkS")
			(hide yes)
			(effects
				(font
					(size 1.27 1.27)
				)
				(justify mirror)
			)
		)
		(property "Value" ""
			(at 0 0 90)
			(layer "B.Fab")
			(effects
				(font
					(size 1.27 1.27)
				)
				(justify mirror)
			)
		)
		(duplicate_pad_numbers_are_jumpers no)
		(fp_line
			(start 0.7874 -0.4064)
			(end -0.7874 -0.4064)
			(stroke
				(width 0.1524)
				(type default)
			)
			(layer "B.SilkS")
		)
		(fp_line
			(start -0.7874 -0.4064)
			(end -0.7874 0.4064)
			(stroke
				(width 0.1524)
				(type default)
			)
			(layer "B.SilkS")
		)
		(fp_line
			(start 0.7874 0.4064)
			(end 0.7874 -0.4064)
			(stroke
				(width 0.1524)
				(type default)
			)
			(layer "B.SilkS")
		)
		(fp_line
			(start -0.7874 0.4064)
			(end 0.7874 0.4064)
			(stroke
				(width 0.1524)
				(type default)
			)
			(layer "B.SilkS")
		)
		(fp_line
			(start 0.67945 -0.305054)
			(end 0.12065 -0.305054)
			(stroke
				(width 0.1)
				(type default)
			)
			(layer "B.Fab")
		)
		(fp_line
			(start 0.12065 -0.305054)
			(end 0.12065 -0.2794)
			(stroke
				(width 0.1)
				(type default)
			)
			(layer "B.Fab")
		)
		(fp_line
			(start -0.12065 -0.3048)
			(end -0.67945 -0.3048)
			(stroke
				(width 0.1)
				(type default)
			)
			(layer "B.Fab")
		)
		(fp_line
			(start -0.67945 -0.3048)
			(end -0.67945 0.3048)
			(stroke
				(width 0.1)
				(type default)
			)
			(layer "B.Fab")
		)
		(fp_line
			(start 0.12065 -0.2794)
			(end -0.12065 -0.2794)
			(stroke
				(width 0.1)
				(type default)
			)
			(layer "B.Fab")
		)
		(fp_line
			(start -0.12065 -0.2794)
			(end -0.12065 -0.3048)
			(stroke
				(width 0.1)
				(type default)
			)
			(layer "B.Fab")
		)
		(fp_line
			(start 0.12065 0.2794)
			(end 0.12065 0.3048)
			(stroke
				(width 0.1)
				(type default)
			)
			(layer "B.Fab")
		)
		(fp_line
			(start -0.120396 0.2794)
			(end 0.12065 0.2794)
			(stroke
				(width 0.1)
				(type default)
			)
			(layer "B.Fab")
		)
		(fp_line
			(start 0.67945 0.3048)
			(end 0.67945 -0.305054)
			(stroke
				(width 0.1)
				(type default)
			)
			(layer "B.Fab")
		)
		(fp_line
			(start 0.12065 0.3048)
			(end 0.67945 0.3048)
			(stroke
				(width 0.1)
				(type default)
			)
			(layer "B.Fab")
		)
		(fp_line
			(start -0.120396 0.3048)
			(end -0.120396 0.2794)
			(stroke
				(width 0.1)
				(type default)
			)
			(layer "B.Fab")
		)
		(fp_line
			(start -0.67945 0.3048)
			(end -0.120396 0.3048)
			(stroke
				(width 0.1)
				(type default)
			)
			(layer "B.Fab")
		)
		(pad "1" smd circle
			(at 0.40005 0 270)
			(size 0 0)
			(layers "B.Cu" "B.Mask" "B.Paste")
			(net "SMB_NIC6_LS_SCL")
		)
		(pad "2" smd circle
			(at -0.40005 0 270)
			(size 0 0)
			(layers "B.Cu" "B.Mask" "B.Paste")
			(net "SMB_NIC6_LS_R_SCL")
		)
	)
	(footprint ""
		(layer "B.Cu")
		(at 339.694012 -217.187018 90)
		(property "Reference" "C2079"
			(at 0 0 90)
			(layer "B.SilkS")
			(hide yes)
			(effects
				(font
					(size 1.27 1.27)
				)
				(justify mirror)
			)
		)
		(property "Value" ""
			(at 0 0 90)
			(layer "B.Fab")
			(effects
				(font
					(size 1.27 1.27)
				)
				(justify mirror)
			)
		)
		(duplicate_pad_numbers_are_jumpers no)
		(fp_line
			(start 0.69215 -0.2921)
			(end -0.69215 -0.2921)
			(stroke
				(width 0.1524)
				(type default)
			)
			(layer "B.SilkS")
		)
		(fp_line
			(start -0.69215 -0.2921)
			(end -0.69215 0.2921)
			(stroke
				(width 0.1524)
				(type default)
			)
			(layer "B.SilkS")
		)
		(fp_line
			(start 0.69215 0.2921)
			(end 0.69215 -0.2921)
			(stroke
				(width 0.1524)
				(type default)
			)
			(layer "B.SilkS")
		)
		(fp_line
			(start -0.69215 0.2921)
			(end 0.69215 0.2921)
			(stroke
				(width 0.1524)
				(type default)
			)
			(layer "B.SilkS")
		)
		(fp_line
			(start 0.51435 -0.2794)
			(end -0.51435 -0.2794)
			(stroke
				(width 0.1)
				(type default)
			)
			(layer "B.Fab")
		)
		(fp_line
			(start -0.51435 -0.2794)
			(end -0.51435 0.2794)
			(stroke
				(width 0.1)
				(type default)
			)
			(layer "B.Fab")
		)
		(fp_line
			(start 0.51435 0.2794)
			(end 0.51435 -0.2794)
			(stroke
				(width 0.1)
				(type default)
			)
			(layer "B.Fab")
		)
		(fp_line
			(start -0.51435 0.2794)
			(end 0.51435 0.2794)
			(stroke
				(width 0.1)
				(type default)
			)
			(layer "B.Fab")
		)
		(pad "1" smd circle
			(at 0.40005 0 270)
			(size 0 0)
			(layers "B.Cu" "B.Mask" "B.Paste")
			(net "P3V3_FPGA_VCCIO3")
		)
		(pad "2" smd circle
			(at -0.40005 0 270)
			(size 0 0)
			(layers "B.Cu" "B.Mask" "B.Paste")
			(net "GND")
		)
		(zone
			(layer "B.Cu")
			(hatch none 0.5)
			(connect_pads
				(clearance 0)
			)
			(min_thickness 0.25)
			(keepout
				(tracks not_allowed)
				(vias allowed)
				(pads allowed)
				(copperpour not_allowed)
				(footprints allowed)
			)
			(placement
				(enabled no)
				(sheetname "")
			)
			(fill
				(thermal_gap 0.5)
				(thermal_bridge_width 0.5)
				(island_removal_mode 0)
			)
			(polygon
				(pts
					(xy 339.781642 -217.377518) (xy 339.839808 -217.286078) (xy 339.839808 -217.086688) (xy 339.781642 -216.996518)
					(xy 339.606382 -216.996518) (xy 339.547962 -217.086688) (xy 339.547962 -217.286078) (xy 339.606128 -217.377518)
				)
			)
		)
	)
	(footprint ""
		(layer "B.Cu")
		(at 407.467816 -286.18434 90)
		(property "Reference" "C3467"
			(at 0 0 90)
			(layer "B.SilkS")
			(hide yes)
			(effects
				(font
					(size 1.27 1.27)
				)
				(justify mirror)
			)
		)
		(property "Value" ""
			(at 0 0 90)
			(layer "B.Fab")
			(effects
				(font
					(size 1.27 1.27)
				)
				(justify mirror)
			)
		)
		(duplicate_pad_numbers_are_jumpers no)
		(fp_line
			(start 1.2954 -0.5842)
			(end -1.2954 -0.5842)
			(stroke
				(width 0.1524)
				(type default)
			)
			(layer "B.SilkS")
		)
		(fp_line
			(start -1.2954 -0.5842)
			(end -1.2954 0.5842)
			(stroke
				(width 0.1524)
				(type default)
			)
			(layer "B.SilkS")
		)
		(fp_line
			(start 1.2954 0.5842)
			(end 1.2954 -0.5842)
			(stroke
				(width 0.1524)
				(type default)
			)
			(layer "B.SilkS")
		)
		(fp_line
			(start -1.2954 0.5842)
			(end 1.2954 0.5842)
			(stroke
				(width 0.1524)
				(type default)
			)
			(layer "B.SilkS")
		)
		(fp_line
			(start 0.8636 -0.4572)
			(end -0.8636 -0.4572)
			(stroke
				(width 0.1)
				(type default)
			)
			(layer "B.Fab")
		)
		(fp_line
			(start -0.8636 -0.4572)
			(end -0.8636 -0.4064)
			(stroke
				(width 0.1)
				(type default)
			)
			(layer "B.Fab")
		)
		(fp_line
			(start 1.1938 -0.4064)
			(end 0.8636 -0.4064)
			(stroke
				(width 0.1)
				(type default)
			)
			(layer "B.Fab")
		)
		(fp_line
			(start 0.8636 -0.4064)
			(end 0.8636 -0.4572)
			(stroke
				(width 0.1)
				(type default)
			)
			(layer "B.Fab")
		)
		(fp_line
			(start -0.8636 -0.4064)
			(end -1.1938 -0.4064)
			(stroke
				(width 0.1)
				(type default)
			)
			(layer "B.Fab")
		)
		(fp_line
			(start -1.1938 -0.4064)
			(end -1.1938 0.4064)
			(stroke
				(width 0.1)
				(type default)
			)
			(layer "B.Fab")
		)
		(fp_line
			(start 1.1938 0.4064)
			(end 1.1938 -0.4064)
			(stroke
				(width 0.1)
				(type default)
			)
			(layer "B.Fab")
		)
		(fp_line
			(start 0.8636 0.4064)
			(end 1.1938 0.4064)
			(stroke
				(width 0.1)
				(type default)
			)
			(layer "B.Fab")
		)
		(fp_line
			(start -0.8636 0.4064)
			(end -0.8636 0.4572)
			(stroke
				(width 0.1)
				(type default)
			)
			(layer "B.Fab")
		)
		(fp_line
			(start -1.1938 0.4064)
			(end -0.8636 0.4064)
			(stroke
				(width 0.1)
				(type default)
			)
			(layer "B.Fab")
		)
		(fp_line
			(start 0.8636 0.4572)
			(end 0.8636 0.4064)
			(stroke
				(width 0.1)
				(type default)
			)
			(layer "B.Fab")
		)
		(fp_line
			(start -0.8636 0.4572)
			(end 0.8636 0.4572)
			(stroke
				(width 0.1)
				(type default)
			)
			(layer "B.Fab")
		)
		(pad "1" smd rect
			(at 0.7366 0)
			(size 0.7112 0.8128)
			(layers "B.Cu" "B.Mask" "B.Paste")
			(net "P1V25_SERDES_VDDPLL_PEX3")
		)
		(pad "2" smd rect
			(at -0.7366 0)
			(size 0.7112 0.8128)
			(layers "B.Cu" "B.Mask" "B.Paste")
			(net "GND")
		)
	)
	(footprint ""
		(layer "B.Cu")
		(at 162.450018 -290.674806)
		(property "Reference" "C3180"
			(at 0 0 0)
			(layer "B.SilkS")
			(hide yes)
			(effects
				(font
					(size 1.27 1.27)
				)
				(justify mirror)
			)
		)
		(property "Value" ""
			(at 0 0 0)
			(layer "B.Fab")
			(effects
				(font
					(size 1.27 1.27)
				)
				(justify mirror)
			)
		)
		(duplicate_pad_numbers_are_jumpers no)
		(fp_line
			(start -0.299974 -0.150114)
			(end -0.299974 0.150114)
			(stroke
				(width 0.1)
				(type default)
			)
			(layer "B.Fab")
		)
		(fp_line
			(start -0.299974 0.150114)
			(end 0.299974 0.150114)
			(stroke
				(width 0.1)
				(type default)
			)
			(layer "B.Fab")
		)
		(fp_line
			(start 0.299974 -0.150114)
			(end -0.299974 -0.150114)
			(stroke
				(width 0.1)
				(type default)
			)
			(layer "B.Fab")
		)
		(fp_line
			(start 0.299974 0.150114)
			(end 0.299974 -0.150114)
			(stroke
				(width 0.1)
				(type default)
			)
			(layer "B.Fab")
		)
		(pad "1" smd rect
			(at 0.2667 0 180)
			(size 0.3048 0.381)
			(layers "B.Cu" "B.Mask" "B.Paste")
			(net "P1V8_PEX")
		)
		(pad "2" smd rect
			(at -0.2667 0 180)
			(size 0.3048 0.381)
			(layers "B.Cu" "B.Mask" "B.Paste")
			(net "GND")
		)
	)
	(footprint ""
		(layer "B.Cu")
		(at 44.449746 -298.27474)
		(property "Reference" "C3007"
			(at 0 0 0)
			(layer "B.SilkS")
			(hide yes)
			(effects
				(font
					(size 1.27 1.27)
				)
				(justify mirror)
			)
		)
		(property "Value" ""
			(at 0 0 0)
			(layer "B.Fab")
			(effects
				(font
					(size 1.27 1.27)
				)
				(justify mirror)
			)
		)
		(duplicate_pad_numbers_are_jumpers no)
		(fp_line
			(start -0.299974 -0.150114)
			(end -0.299974 0.150114)
			(stroke
				(width 0.1)
				(type default)
			)
			(layer "B.Fab")
		)
		(fp_line
			(start -0.299974 0.150114)
			(end 0.299974 0.150114)
			(stroke
				(width 0.1)
				(type default)
			)
			(layer "B.Fab")
		)
		(fp_line
			(start 0.299974 -0.150114)
			(end -0.299974 -0.150114)
			(stroke
				(width 0.1)
				(type default)
			)
			(layer "B.Fab")
		)
		(fp_line
			(start 0.299974 0.150114)
			(end 0.299974 -0.150114)
			(stroke
				(width 0.1)
				(type default)
			)
			(layer "B.Fab")
		)
		(pad "1" smd rect
			(at 0.2667 0 180)
			(size 0.3048 0.381)
			(layers "B.Cu" "B.Mask" "B.Paste")
			(net "P1V8_VDDA_PEX0")
		)
		(pad "2" smd rect
			(at -0.2667 0 180)
			(size 0.3048 0.381)
			(layers "B.Cu" "B.Mask" "B.Paste")
			(net "GND")
		)
	)
	(footprint ""
		(layer "B.Cu")
		(at 257.264916 -366.906048 180)
		(property "Reference" "PR6610"
			(at 0 0 0)
			(layer "B.SilkS")
			(hide yes)
			(effects
				(font
					(size 1.27 1.27)
				)
				(justify mirror)
			)
		)
		(property "Value" ""
			(at 0 0 0)
			(layer "B.Fab")
			(effects
				(font
					(size 1.27 1.27)
				)
				(justify mirror)
			)
		)
		(duplicate_pad_numbers_are_jumpers no)
		(fp_line
			(start 0.7874 0.4064)
			(end 0.7874 -0.4064)
			(stroke
				(width 0.1524)
				(type default)
			)
			(layer "B.SilkS")
		)
		(fp_line
			(start 0.7874 -0.4064)
			(end -0.7874 -0.4064)
			(stroke
				(width 0.1524)
				(type default)
			)
			(layer "B.SilkS")
		)
		(fp_line
			(start -0.7874 0.4064)
			(end 0.7874 0.4064)
			(stroke
				(width 0.1524)
				(type default)
			)
			(layer "B.SilkS")
		)
		(fp_line
			(start -0.7874 -0.4064)
			(end -0.7874 0.4064)
			(stroke
				(width 0.1524)
				(type default)
			)
			(layer "B.SilkS")
		)
		(fp_line
			(start 0.67945 0.3048)
			(end 0.67945 -0.305054)
			(stroke
				(width 0.1)
				(type default)
			)
			(layer "B.Fab")
		)
		(fp_line
			(start 0.67945 -0.305054)
			(end 0.12065 -0.305054)
			(stroke
				(width 0.1)
				(type default)
			)
			(layer "B.Fab")
		)
		(fp_line
			(start 0.12065 0.3048)
			(end 0.67945 0.3048)
			(stroke
				(width 0.1)
				(type default)
			)
			(layer "B.Fab")
		)
		(fp_line
			(start 0.12065 0.2794)
			(end 0.12065 0.3048)
			(stroke
				(width 0.1)
				(type default)
			)
			(layer "B.Fab")
		)
		(fp_line
			(start 0.12065 -0.2794)
			(end -0.12065 -0.2794)
			(stroke
				(width 0.1)
				(type default)
			)
			(layer "B.Fab")
		)
		(fp_line
			(start 0.12065 -0.305054)
			(end 0.12065 -0.2794)
			(stroke
				(width 0.1)
				(type default)
			)
			(layer "B.Fab")
		)
		(fp_line
			(start -0.120396 0.3048)
			(end -0.120396 0.2794)
			(stroke
				(width 0.1)
				(type default)
			)
			(layer "B.Fab")
		)
		(fp_line
			(start -0.120396 0.2794)
			(end 0.12065 0.2794)
			(stroke
				(width 0.1)
				(type default)
			)
			(layer "B.Fab")
		)
		(fp_line
			(start -0.12065 -0.2794)
			(end -0.12065 -0.3048)
			(stroke
				(width 0.1)
				(type default)
			)
			(layer "B.Fab")
		)
		(fp_line
			(start -0.12065 -0.3048)
			(end -0.67945 -0.3048)
			(stroke
				(width 0.1)
				(type default)
			)
			(layer "B.Fab")
		)
		(fp_line
			(start -0.67945 0.3048)
			(end -0.120396 0.3048)
			(stroke
				(width 0.1)
				(type default)
			)
			(layer "B.Fab")
		)
		(fp_line
			(start -0.67945 -0.3048)
			(end -0.67945 0.3048)
			(stroke
				(width 0.1)
				(type default)
			)
			(layer "B.Fab")
		)
		(pad "1" smd circle
			(at 0.40005 0)
			(size 0 0)
			(layers "B.Cu" "B.Mask" "B.Paste")
			(net "P12V_HSC_GATE2")
		)
		(pad "2" smd circle
			(at -0.40005 0)
			(size 0 0)
			(layers "B.Cu" "B.Mask" "B.Paste")
			(net "HS_GATE2_R_3")
		)
	)
	(footprint ""
		(layer "B.Cu")
		(at 51.099974 -292.099746 90)
		(property "Reference" "C1185"
			(at 0 0 90)
			(layer "B.SilkS")
			(hide yes)
			(effects
				(font
					(size 1.27 1.27)
				)
				(justify mirror)
			)
		)
		(property "Value" ""
			(at 0 0 90)
			(layer "B.Fab")
			(effects
				(font
					(size 1.27 1.27)
				)
				(justify mirror)
			)
		)
		(duplicate_pad_numbers_are_jumpers no)
		(fp_line
			(start 0.299974 -0.150114)
			(end -0.299974 -0.150114)
			(stroke
				(width 0.1)
				(type default)
			)
			(layer "B.Fab")
		)
		(fp_line
			(start -0.299974 -0.150114)
			(end -0.299974 0.150114)
			(stroke
				(width 0.1)
				(type default)
			)
			(layer "B.Fab")
		)
		(fp_line
			(start 0.299974 0.150114)
			(end 0.299974 -0.150114)
			(stroke
				(width 0.1)
				(type default)
			)
			(layer "B.Fab")
		)
		(fp_line
			(start -0.299974 0.150114)
			(end 0.299974 0.150114)
			(stroke
				(width 0.1)
				(type default)
			)
			(layer "B.Fab")
		)
		(pad "1" smd rect
			(at 0.2667 0 270)
			(size 0.3048 0.381)
			(layers "B.Cu" "B.Mask" "B.Paste")
			(net "P0V8_SERDES_VDDA_PEX0")
		)
		(pad "2" smd rect
			(at -0.2667 0 270)
			(size 0.3048 0.381)
			(layers "B.Cu" "B.Mask" "B.Paste")
			(net "GND")
		)
	)
)
